# TIMECARD (Time Appliance Project (Time Card)) — schematic netlist excerpt (pin names and nets, part order shuffled) for the footprints in the layout excerpt that follows; sources: Cadence DE-HDL packaged netlist, KiCad conversion of R4006-B0001-02_R01.brd

C73  CAPACITOR  0.1UF 25V 10%  pkg SMC_0402R_H022  page 22 : \1\ = XP5R0V_VCC_ANT ; \2\ = SG
R168  RESISTOR  1MOHM 1%  pkg SMC_0402R_H016  page 20 : \1\ = UNNAMED_9_CAPACITOR_I17_1 ; \2\ = UNNAMED_9_BNO080LGA28_I29_XOUT3

(kicad_pcb
	(version 20260206)
	(generator "pcbnew")
	(generator_version "10.0")
	(general
		(thickness 1.6)
		(legacy_teardrops no)
	)
	(paper "A4")
	(title_block
		(title "timecard-production-celestica-r4006 — R4006-B0001-02_R01.brd")
		(comment 1 "Time Appliance Project (Time Card) / footprints 978-979 of 1113")
	)
	(layers
		(0 "F.Cu" signal "TOP")
		(4 "In1.Cu" signal "L02_GND1")
		(6 "In2.Cu" signal "L03_SIG1")
		(8 "In3.Cu" signal "L04_GND2")
		(10 "In4.Cu" signal "L05_VCC1")
		(12 "In5.Cu" signal "L06_VCC2")
		(14 "In6.Cu" signal "L07_GND3")
		(16 "In7.Cu" signal "L08_SIG2")
		(18 "In8.Cu" signal "L09_GND4")
		(2 "B.Cu" signal "BOTTOM")
		(9 "F.Adhes" user "F.Adhesive")
		(11 "B.Adhes" user "B.Adhesive")
		(13 "F.Paste" user "Package Geometry/Pastemask Top")
		(15 "B.Paste" user "Package Geometry/Pastemask Bottom")
		(5 "F.SilkS" user "Ref Des/Silkscreen Top")
		(7 "B.SilkS" user "Ref Des/Silkscreen Bottom")
		(1 "F.Mask" user "Board Geometry/Soldermask Top")
		(3 "B.Mask" user "Board Geometry/Soldermask Bottom")
		(17 "Dwgs.User" user "User.Drawings")
		(19 "Cmts.User" user "User.Comments")
		(21 "Eco1.User" user "User.Eco1")
		(23 "Eco2.User" user "User.Eco2")
		(25 "Edge.Cuts" user "Board Geometry/Outline")
		(27 "Margin" user)
		(31 "F.CrtYd" user "Package Geometry/Place Bound Top")
		(29 "B.CrtYd" user "Package Geometry/Place Bound Bottom")
		(35 "F.Fab" user "Ref Des/Assembly Top")
		(33 "B.Fab" user "Ref Des/Assembly Bottom")
	)
	(footprint ""
		(layer "B.Cu")
		(at 129.159 -98.425 90)
		(property "Reference" "C73"
			(at -2.667 0.08763 270)
			(unlocked yes)
			(layer "B.SilkS")
			(effects
				(font
					(size 0.7874 0.5842)
					(thickness 0.1524)
				)
				(justify mirror)
			)
		)
		(property "Value" "VAL*"
			(at -0.0762 2.067306 90)
			(unlocked yes)
			(layer "B.Fab")
			(hide yes)
			(effects
				(font
					(size 0.7874 0.5842)
					(thickness 0.1524)
				)
				(justify mirror)
			)
		)
		(property "Device Type" "CAPACITOR-G105-0B104-EK,0.1UF,A"
			(at -0.0508 1.127506 90)
			(unlocked yes)
			(layer "B.Fab")
			(hide yes)
			(effects
				(font
					(size 0.7874 0.5842)
					(thickness 0.1524)
				)
				(justify mirror)
			)
		)
		(property "User Part Number" "PARTNUM*"
			(at -0.1016 4.023106 90)
			(unlocked yes)
			(layer "Cmts.User")
			(hide yes)
			(effects
				(font
					(size 0.7874 0.5842)
					(thickness 0.1524)
				)
				(justify mirror)
			)
		)
		(property "Tolerance" "TOL*"
			(at -0.0762 3.032506 90)
			(unlocked yes)
			(layer "Cmts.User")
			(hide yes)
			(effects
				(font
					(size 0.7874 0.5842)
					(thickness 0.1524)
				)
				(justify mirror)
			)
		)
		(duplicate_pad_numbers_are_jumpers no)
		(fp_line
			(start 1.143 -0.5588)
			(end 1.143 0.5588)
			(stroke
				(width 0.1)
				(type default)
			)
			(layer "B.SilkS")
		)
		(fp_line
			(start -1.143 -0.5588)
			(end 1.143 -0.5588)
			(stroke
				(width 0.1)
				(type default)
			)
			(layer "B.SilkS")
		)
		(fp_line
			(start 1.143 0.5588)
			(end -1.143 0.5588)
			(stroke
				(width 0.1)
				(type default)
			)
			(layer "B.SilkS")
		)
		(fp_line
			(start -1.143 0.5588)
			(end -1.143 -0.5588)
			(stroke
				(width 0.1)
				(type default)
			)
			(layer "B.SilkS")
		)
		(fp_rect
			(start -1.143 -0.5588)
			(end 1.143 0.5588)
			(stroke
				(width 0)
				(type default)
			)
			(fill no)
			(layer "B.CrtYd")
		)
		(fp_line
			(start 0.508 -0.3048)
			(end 0.508 0.3048)
			(stroke
				(width 0.1)
				(type default)
			)
			(layer "B.Fab")
		)
		(fp_line
			(start -0.508 -0.3048)
			(end 0.508 -0.3048)
			(stroke
				(width 0.1)
				(type default)
			)
			(layer "B.Fab")
		)
		(fp_line
			(start 0.508 0.3048)
			(end -0.508 0.3048)
			(stroke
				(width 0.1)
				(type default)
			)
			(layer "B.Fab")
		)
		(fp_line
			(start -0.508 0.3048)
			(end -0.508 -0.3048)
			(stroke
				(width 0.1)
				(type default)
			)
			(layer "B.Fab")
		)
		(pad "1" smd rect
			(at 0.5334 0 270)
			(size 0.7112 0.6096)
			(layers "B.Cu" "B.Mask" "B.Paste")
			(net "XP5R0V_VCC_ANT")
		)
		(pad "2" smd rect
			(at -0.5334 0 270)
			(size 0.7112 0.6096)
			(layers "B.Cu" "B.Mask" "B.Paste")
			(net "SG")
		)
		(zone
			(layer "B.Cu")
			(hatch none 0.5)
			(connect_pads
				(clearance 0)
			)
			(min_thickness 0.25)
			(keepout
				(tracks allowed)
				(vias not_allowed)
				(pads allowed)
				(copperpour not_allowed)
				(footprints allowed)
			)
			(placement
				(enabled no)
				(sheetname "")
			)
			(fill
				(thermal_gap 0.5)
				(thermal_bridge_width 0.5)
				(island_removal_mode 0)
			)
			(polygon
				(pts
					(xy 128.8542 -98.3488) (xy 129.4638 -98.3488) (xy 129.4638 -98.5012) (xy 128.8542 -98.5012)
				)
			)
		)
	)
	(footprint ""
		(layer "B.Cu")
		(at 88.138 -59.817 90)
		(property "Reference" "R168"
			(at 2.794 0.21463 270)
			(unlocked yes)
			(layer "B.SilkS")
			(effects
				(font
					(size 0.7874 0.5842)
					(thickness 0.1524)
				)
				(justify mirror)
			)
		)
		(property "Value" "VAL*"
			(at -0.02032 2.13233 90)
			(unlocked yes)
			(layer "B.Fab")
			(hide yes)
			(effects
				(font
					(size 0.7874 0.5842)
					(thickness 0.1524)
				)
				(justify mirror)
			)
		)
		(property "Tolerance" "TOL*"
			(at -0.044704 3.05435 90)
			(unlocked yes)
			(layer "Cmts.User")
			(hide yes)
			(effects
				(font
					(size 0.7874 0.5842)
					(thickness 0.1524)
				)
				(justify mirror)
			)
		)
		(property "User Part Number" "PARTNUM*"
			(at -0.02032 4.024884 90)
			(unlocked yes)
			(layer "Cmts.User")
			(hide yes)
			(effects
				(font
					(size 0.7874 0.5842)
					(thickness 0.1524)
				)
				(justify mirror)
			)
		)
		(property "Device Type" "RESISTOR-G155-11004-01,1MOHM,1%"
			(at -0.008382 1.210564 90)
			(unlocked yes)
			(layer "B.Fab")
			(hide yes)
			(effects
				(font
					(size 0.7874 0.5842)
					(thickness 0.1524)
				)
				(justify mirror)
			)
		)
		(duplicate_pad_numbers_are_jumpers no)
		(fp_line
			(start 1.143 -0.5588)
			(end 1.143 0.5588)
			(stroke
				(width 0.1)
				(type default)
			)
			(layer "B.SilkS")
		)
		(fp_line
			(start -1.143 -0.5588)
			(end 1.143 -0.5588)
			(stroke
				(width 0.1)
				(type default)
			)
			(layer "B.SilkS")
		)
		(fp_line
			(start 1.143 0.5588)
			(end -1.143 0.5588)
			(stroke
				(width 0.1)
				(type default)
			)
			(layer "B.SilkS")
		)
		(fp_line
			(start -1.143 0.5588)
			(end -1.143 -0.5588)
			(stroke
				(width 0.1)
				(type default)
			)
			(layer "B.SilkS")
		)
		(fp_rect
			(start -1.143 -0.5588)
			(end 1.143 0.5588)
			(stroke
				(width 0)
				(type default)
			)
			(fill no)
			(layer "B.CrtYd")
		)
		(fp_line
			(start 0.508 -0.3048)
			(end 0.508 0.3048)
			(stroke
				(width 0.1)
				(type default)
			)
			(layer "B.Fab")
		)
		(fp_line
			(start -0.508 -0.3048)
			(end 0.508 -0.3048)
			(stroke
				(width 0.1)
				(type default)
			)
			(layer "B.Fab")
		)
		(fp_line
			(start 0.508 0.3048)
			(end -0.508 0.3048)
			(stroke
				(width 0.1)
				(type default)
			)
			(layer "B.Fab")
		)
		(fp_line
			(start -0.508 0.3048)
			(end -0.508 -0.3048)
			(stroke
				(width 0.1)
				(type default)
			)
			(layer "B.Fab")
		)
		(pad "1" smd rect
			(at 0.5334 0 270)
			(size 0.7112 0.6096)
			(layers "B.Cu" "B.Mask" "B.Paste")
			(net "UNNAMED_9_CAPACITOR_I17_1")
		)
		(pad "2" smd rect
			(at -0.5334 0 270)
			(size 0.7112 0.6096)
			(layers "B.Cu" "B.Mask" "B.Paste")
			(net "UNNAMED_9_BNO080LGA28_I29_XOUT3")
		)
		(zone
			(layer "B.Cu")
			(hatch none 0.5)
			(connect_pads
				(clearance 0)
			)
			(min_thickness 0.25)
			(keepout
				(tracks allowed)
				(vias not_allowed)
				(pads allowed)
				(copperpour not_allowed)
				(footprints allowed)
			)
			(placement
				(enabled no)
				(sheetname "")
			)
			(fill
				(thermal_gap 0.5)
				(thermal_bridge_width 0.5)
				(island_removal_mode 0)
			)
			(polygon
				(pts
					(xy 87.8332 -59.7408) (xy 88.4428 -59.7408) (xy 88.4428 -59.8932) (xy 87.8332 -59.8932)
				)
			)
		)
	)
)
